(kicad_pcb
	(version 20260206)
	(generator "pcbnew")
	(generator_version "10.0")
	(general
		(thickness 1.6)
		(legacy_teardrops no)
	)
	(paper "A4")
	(title_block
		(title "v1-chassis-manager — T6M_CM_d_v01_1031_1645.brd")
		(comment 1 "Open CloudServer (Microsoft) / footprints 2153-2163 of 2512")
	)
	(layers
		(0 "F.Cu" signal "TOP")
		(4 "In1.Cu" signal "GND1")
		(6 "In2.Cu" signal "IN1")
		(8 "In3.Cu" signal "VCC1")
		(10 "In4.Cu" signal "VCC2")
		(12 "In5.Cu" signal "GND2")
		(14 "In6.Cu" signal "IN2")
		(16 "In7.Cu" signal "IN3")
		(18 "In8.Cu" signal "GND3")
		(2 "B.Cu" signal "BOTTOM")
		(9 "F.Adhes" user "F.Adhesive")
		(11 "B.Adhes" user "B.Adhesive")
		(13 "F.Paste" user "Package Geometry/Pastemask Top")
		(15 "B.Paste" user "Package Geometry/Pastemask Bottom")
		(5 "F.SilkS" user "Ref Des/Silkscreen Top")
		(7 "B.SilkS" user "Ref Des/Silkscreen Bottom")
		(1 "F.Mask" user "Board Geometry/Soldermask Top")
		(3 "B.Mask" user "Board Geometry/Soldermask Bottom")
		(17 "Dwgs.User" user "User.Drawings")
		(19 "Cmts.User" user "User.Comments")
		(21 "Eco1.User" user "User.Eco1")
		(23 "Eco2.User" user "User.Eco2")
		(25 "Edge.Cuts" user "Board Geometry/Outline")
		(27 "Margin" user)
		(31 "F.CrtYd" user "Package Geometry/Place Bound Top")
		(29 "B.CrtYd" user "Package Geometry/Place Bound Bottom")
		(35 "F.Fab" user "Ref Des/Assembly Top")
		(33 "B.Fab" user "Ref Des/Assembly Bottom")
	)
	(footprint ""
		(layer "B.Cu")
		(at 69.987668 -21.171662 90)
		(property "Reference" "C158"
			(at -5.88137 -0.810006 270)
			(unlocked yes)
			(layer "B.SilkS")
			(effects
				(font
					(size 0.7874 0.5842)
					(thickness 0.1524)
				)
				(justify left mirror)
			)
		)
		(property "Value" ""
			(at 0 0 90)
			(layer "B.Fab")
			(effects
				(font
					(size 1.27 1.27)
				)
				(justify mirror)
			)
		)
		(duplicate_pad_numbers_are_jumpers no)
		(fp_line
			(start 0.7874 -0.4064)
			(end -0.7874 -0.4064)
			(stroke
				(width 0.1524)
				(type default)
			)
			(layer "B.SilkS")
		)
		(fp_line
			(start -0.7874 -0.4064)
			(end -0.7874 0.4064)
			(stroke
				(width 0.1524)
				(type default)
			)
			(layer "B.SilkS")
		)
		(fp_line
			(start 0 0.381)
			(end 0 -0.381)
			(stroke
				(width 0.1524)
				(type default)
			)
			(layer "B.SilkS")
		)
		(fp_line
			(start 0.7874 0.4064)
			(end 0.7874 -0.4064)
			(stroke
				(width 0.1524)
				(type default)
			)
			(layer "B.SilkS")
		)
		(fp_line
			(start -0.7874 0.4064)
			(end 0.7874 0.4064)
			(stroke
				(width 0.1524)
				(type default)
			)
			(layer "B.SilkS")
		)
		(fp_poly
			(pts
				(xy 0.5334 0.254) (xy 0.635 0.254) (xy 0.635 0.2286) (xy 0.635 -0.254) (xy 0.5334 -0.254) (xy 0.5334 -0.2794)
				(xy -0.5334 -0.2794) (xy -0.5334 -0.254) (xy -0.635 -0.254) (xy -0.635 0.254) (xy -0.5334 0.254)
				(xy -0.5334 0.2794) (xy 0.508 0.2794) (xy 0.5334 0.2794)
			)
			(stroke
				(width 0)
				(type default)
			)
			(fill no)
			(layer "B.CrtYd")
		)
		(pad "1" smd rect
			(at -0.40005 0 270)
			(size 0.4572 0.508)
			(layers "B.Cu" "B.Mask" "B.Paste")
			(net "PV_VDDR_NODE1")
		)
		(pad "2" smd rect
			(at 0.40005 0 270)
			(size 0.4572 0.508)
			(layers "B.Cu" "B.Mask" "B.Paste")
			(net "GND")
		)
	)
	(footprint ""
		(layer "B.Cu")
		(at 77.86243 -84.93252)
		(property "Reference" "R143"
			(at -13.49121 31.479744 0)
			(unlocked yes)
			(layer "B.SilkS")
			(effects
				(font
					(size 0.7874 0.5842)
					(thickness 0.1524)
				)
				(justify left mirror)
			)
		)
		(property "Value" ""
			(at 0 0 0)
			(layer "B.Fab")
			(effects
				(font
					(size 1.27 1.27)
				)
				(justify mirror)
			)
		)
		(duplicate_pad_numbers_are_jumpers no)
		(fp_line
			(start -0.7874 -0.4064)
			(end -0.7874 0.4064)
			(stroke
				(width 0.1524)
				(type default)
			)
			(layer "B.SilkS")
		)
		(fp_line
			(start -0.7874 0.4064)
			(end 0.7874 0.4064)
			(stroke
				(width 0.1524)
				(type default)
			)
			(layer "B.SilkS")
		)
		(fp_line
			(start 0.7874 -0.4064)
			(end -0.7874 -0.4064)
			(stroke
				(width 0.1524)
				(type default)
			)
			(layer "B.SilkS")
		)
		(fp_line
			(start 0.7874 0.4064)
			(end 0.7874 -0.4064)
			(stroke
				(width 0.1524)
				(type default)
			)
			(layer "B.SilkS")
		)
		(fp_poly
			(pts
				(xy 0.508 0.2794) (xy 0.508 0.2286) (xy 0.635 0.2286) (xy 0.635 -0.254) (xy 0.5334 -0.254) (xy 0.5334 -0.2794)
				(xy -0.5334 -0.2794) (xy -0.5334 -0.254) (xy -0.635 -0.254) (xy -0.635 0.254) (xy -0.5334 0.254)
				(xy -0.5334 0.2794)
			)
			(stroke
				(width 0)
				(type default)
			)
			(fill no)
			(layer "B.CrtYd")
		)
		(pad "1" smd rect
			(at -0.40005 0 180)
			(size 0.4572 0.508)
			(layers "B.Cu" "B.Mask" "B.Paste")
			(net "N32265582")
		)
		(pad "2" smd rect
			(at 0.40005 0 180)
			(size 0.4572 0.508)
			(layers "B.Cu" "B.Mask" "B.Paste")
			(net "P3V3_RTC_NODE1")
		)
	)
	(footprint ""
		(layer "B.Cu")
		(at 169.779188 -94.36354 90)
		(property "Reference" "C384"
			(at -2.781554 2.10185 270)
			(unlocked yes)
			(layer "B.SilkS")
			(effects
				(font
					(size 0.7874 0.5842)
					(thickness 0.1524)
				)
				(justify left mirror)
			)
		)
		(property "Value" ""
			(at 0 0 90)
			(layer "B.Fab")
			(effects
				(font
					(size 1.27 1.27)
				)
				(justify mirror)
			)
		)
		(duplicate_pad_numbers_are_jumpers no)
		(fp_line
			(start 0.7874 -0.4064)
			(end -0.7874 -0.4064)
			(stroke
				(width 0.1524)
				(type default)
			)
			(layer "B.SilkS")
		)
		(fp_line
			(start -0.7874 -0.4064)
			(end -0.7874 0.4064)
			(stroke
				(width 0.1524)
				(type default)
			)
			(layer "B.SilkS")
		)
		(fp_line
			(start 0 0.381)
			(end 0 -0.381)
			(stroke
				(width 0.1524)
				(type default)
			)
			(layer "B.SilkS")
		)
		(fp_line
			(start 0.7874 0.4064)
			(end 0.7874 -0.4064)
			(stroke
				(width 0.1524)
				(type default)
			)
			(layer "B.SilkS")
		)
		(fp_line
			(start -0.7874 0.4064)
			(end 0.7874 0.4064)
			(stroke
				(width 0.1524)
				(type default)
			)
			(layer "B.SilkS")
		)
		(fp_poly
			(pts
				(xy 0.5334 0.254) (xy 0.635 0.254) (xy 0.635 0.2286) (xy 0.635 -0.254) (xy 0.5334 -0.254) (xy 0.5334 -0.2794)
				(xy -0.5334 -0.2794) (xy -0.5334 -0.254) (xy -0.635 -0.254) (xy -0.635 0.254) (xy -0.5334 0.254)
				(xy -0.5334 0.2794) (xy 0.508 0.2794) (xy 0.5334 0.2794)
			)
			(stroke
				(width 0)
				(type default)
			)
			(fill no)
			(layer "B.CrtYd")
		)
		(pad "1" smd rect
			(at -0.40005 0 270)
			(size 0.4572 0.508)
			(layers "B.Cu" "B.Mask" "B.Paste")
			(net "GND")
		)
		(pad "2" smd rect
			(at 0.40005 0 270)
			(size 0.4572 0.508)
			(layers "B.Cu" "B.Mask" "B.Paste")
			(net "P3V3_USB_NODE1")
		)
	)
	(footprint ""
		(layer "B.Cu")
		(at 63.959486 -140.805662 90)
		(property "Reference" "C242"
			(at -54.612794 -41.514776 270)
			(unlocked yes)
			(layer "B.SilkS")
			(effects
				(font
					(size 0.7874 0.5842)
					(thickness 0.1524)
				)
				(justify left mirror)
			)
		)
		(property "Value" ""
			(at 0 0 90)
			(layer "B.Fab")
			(effects
				(font
					(size 1.27 1.27)
				)
				(justify mirror)
			)
		)
		(duplicate_pad_numbers_are_jumpers no)
		(fp_line
			(start 0.7874 -0.4064)
			(end -0.7874 -0.4064)
			(stroke
				(width 0.1524)
				(type default)
			)
			(layer "B.SilkS")
		)
		(fp_line
			(start -0.7874 -0.4064)
			(end -0.7874 0.4064)
			(stroke
				(width 0.1524)
				(type default)
			)
			(layer "B.SilkS")
		)
		(fp_line
			(start 0 0.381)
			(end 0 -0.381)
			(stroke
				(width 0.1524)
				(type default)
			)
			(layer "B.SilkS")
		)
		(fp_line
			(start 0.7874 0.4064)
			(end 0.7874 -0.4064)
			(stroke
				(width 0.1524)
				(type default)
			)
			(layer "B.SilkS")
		)
		(fp_line
			(start -0.7874 0.4064)
			(end 0.7874 0.4064)
			(stroke
				(width 0.1524)
				(type default)
			)
			(layer "B.SilkS")
		)
		(fp_poly
			(pts
				(xy 0.5334 0.254) (xy 0.635 0.254) (xy 0.635 0.2286) (xy 0.635 -0.254) (xy 0.5334 -0.254) (xy 0.5334 -0.2794)
				(xy -0.5334 -0.2794) (xy -0.5334 -0.254) (xy -0.635 -0.254) (xy -0.635 0.254) (xy -0.5334 0.254)
				(xy -0.5334 0.2794) (xy 0.508 0.2794) (xy 0.5334 0.2794)
			)
			(stroke
				(width 0)
				(type default)
			)
			(fill no)
			(layer "B.CrtYd")
		)
		(pad "1" smd rect
			(at -0.40005 0 270)
			(size 0.4572 0.508)
			(layers "B.Cu" "B.Mask" "B.Paste")
			(net "P3V3_NODE1")
		)
		(pad "2" smd rect
			(at 0.40005 0 270)
			(size 0.4572 0.508)
			(layers "B.Cu" "B.Mask" "B.Paste")
			(net "GND")
		)
	)
	(footprint ""
		(layer "B.Cu")
		(at 67.286886 -121.044462 90)
		(property "Reference" "R335"
			(at -7.37235 9.88314 270)
			(unlocked yes)
			(layer "B.SilkS")
			(effects
				(font
					(size 0.7874 0.5842)
					(thickness 0.1524)
				)
				(justify left mirror)
			)
		)
		(property "Value" ""
			(at 0 0 90)
			(layer "B.Fab")
			(effects
				(font
					(size 1.27 1.27)
				)
				(justify mirror)
			)
		)
		(duplicate_pad_numbers_are_jumpers no)
		(fp_line
			(start 0.7874 -0.4064)
			(end -0.7874 -0.4064)
			(stroke
				(width 0.1524)
				(type default)
			)
			(layer "B.SilkS")
		)
		(fp_line
			(start -0.7874 -0.4064)
			(end -0.7874 0.4064)
			(stroke
				(width 0.1524)
				(type default)
			)
			(layer "B.SilkS")
		)
		(fp_line
			(start 0.7874 0.4064)
			(end 0.7874 -0.4064)
			(stroke
				(width 0.1524)
				(type default)
			)
			(layer "B.SilkS")
		)
		(fp_line
			(start -0.7874 0.4064)
			(end 0.7874 0.4064)
			(stroke
				(width 0.1524)
				(type default)
			)
			(layer "B.SilkS")
		)
		(fp_poly
			(pts
				(xy 0.508 0.2794) (xy 0.508 0.2286) (xy 0.635 0.2286) (xy 0.635 -0.254) (xy 0.5334 -0.254) (xy 0.5334 -0.2794)
				(xy -0.5334 -0.2794) (xy -0.5334 -0.254) (xy -0.635 -0.254) (xy -0.635 0.254) (xy -0.5334 0.254)
				(xy -0.5334 0.2794)
			)
			(stroke
				(width 0)
				(type default)
			)
			(fill no)
			(layer "B.CrtYd")
		)
		(pad "1" smd rect
			(at -0.40005 0 270)
			(size 0.4572 0.508)
			(layers "B.Cu" "B.Mask" "B.Paste")
			(net "P3V3_NODE1")
		)
		(pad "2" smd rect
			(at 0.40005 0 270)
			(size 0.4572 0.508)
			(layers "B.Cu" "B.Mask" "B.Paste")
			(net "BMC_ROMA19")
		)
	)
	(footprint ""
		(layer "B.Cu")
		(at 63.15075 -69.200268 90)
		(property "Reference" "C132"
			(at -34.07156 -14.28242 270)
			(unlocked yes)
			(layer "B.SilkS")
			(effects
				(font
					(size 0.7874 0.5842)
					(thickness 0.1524)
				)
				(justify left mirror)
			)
		)
		(property "Value" ""
			(at 0 0 90)
			(layer "B.Fab")
			(effects
				(font
					(size 1.27 1.27)
				)
				(justify mirror)
			)
		)
		(duplicate_pad_numbers_are_jumpers no)
		(fp_line
			(start 0.7874 -0.4064)
			(end -0.7874 -0.4064)
			(stroke
				(width 0.1524)
				(type default)
			)
			(layer "B.SilkS")
		)
		(fp_line
			(start -0.7874 -0.4064)
			(end -0.7874 0.4064)
			(stroke
				(width 0.1524)
				(type default)
			)
			(layer "B.SilkS")
		)
		(fp_line
			(start 0 0.381)
			(end 0 -0.381)
			(stroke
				(width 0.1524)
				(type default)
			)
			(layer "B.SilkS")
		)
		(fp_line
			(start 0.7874 0.4064)
			(end 0.7874 -0.4064)
			(stroke
				(width 0.1524)
				(type default)
			)
			(layer "B.SilkS")
		)
		(fp_line
			(start -0.7874 0.4064)
			(end 0.7874 0.4064)
			(stroke
				(width 0.1524)
				(type default)
			)
			(layer "B.SilkS")
		)
		(fp_poly
			(pts
				(xy 0.5334 0.254) (xy 0.635 0.254) (xy 0.635 0.2286) (xy 0.635 -0.254) (xy 0.5334 -0.254) (xy 0.5334 -0.2794)
				(xy -0.5334 -0.2794) (xy -0.5334 -0.254) (xy -0.635 -0.254) (xy -0.635 0.254) (xy -0.5334 0.254)
				(xy -0.5334 0.2794) (xy 0.508 0.2794) (xy 0.5334 0.2794)
			)
			(stroke
				(width 0)
				(type default)
			)
			(fill no)
			(layer "B.CrtYd")
		)
		(pad "1" smd rect
			(at -0.40005 0 270)
			(size 0.4572 0.508)
			(layers "B.Cu" "B.Mask" "B.Paste")
			(net "PV_VDDR_VCCCLK_DDR3_NODE1")
		)
		(pad "2" smd rect
			(at 0.40005 0 270)
			(size 0.4572 0.508)
			(layers "B.Cu" "B.Mask" "B.Paste")
			(net "GND")
		)
	)
	(footprint ""
		(layer "B.Cu")
		(at 141.259052 -139.22375)
		(property "Reference" "C888"
			(at 3.924046 -3.314954 0)
			(unlocked yes)
			(layer "B.SilkS")
			(effects
				(font
					(size 0.7874 0.5842)
					(thickness 0.1524)
				)
				(justify left mirror)
			)
		)
		(property "Value" ""
			(at 0 0 0)
			(layer "B.Fab")
			(effects
				(font
					(size 1.27 1.27)
				)
				(justify mirror)
			)
		)
		(duplicate_pad_numbers_are_jumpers no)
		(fp_line
			(start -0.7874 -0.4064)
			(end -0.7874 0.4064)
			(stroke
				(width 0.1524)
				(type default)
			)
			(layer "B.SilkS")
		)
		(fp_line
			(start -0.7874 0.4064)
			(end 0.7874 0.4064)
			(stroke
				(width 0.1524)
				(type default)
			)
			(layer "B.SilkS")
		)
		(fp_line
			(start 0 0.381)
			(end 0 -0.381)
			(stroke
				(width 0.1524)
				(type default)
			)
			(layer "B.SilkS")
		)
		(fp_line
			(start 0.7874 -0.4064)
			(end -0.7874 -0.4064)
			(stroke
				(width 0.1524)
				(type default)
			)
			(layer "B.SilkS")
		)
		(fp_line
			(start 0.7874 0.4064)
			(end 0.7874 -0.4064)
			(stroke
				(width 0.1524)
				(type default)
			)
			(layer "B.SilkS")
		)
		(fp_poly
			(pts
				(xy 0.5334 0.254) (xy 0.635 0.254) (xy 0.635 0.2286) (xy 0.635 -0.254) (xy 0.5334 -0.254) (xy 0.5334 -0.2794)
				(xy -0.5334 -0.2794) (xy -0.5334 -0.254) (xy -0.635 -0.254) (xy -0.635 0.254) (xy -0.5334 0.254)
				(xy -0.5334 0.2794) (xy 0.508 0.2794) (xy 0.5334 0.2794)
			)
			(stroke
				(width 0)
				(type default)
			)
			(fill no)
			(layer "B.CrtYd")
		)
		(pad "1" smd rect
			(at -0.40005 0 180)
			(size 0.4572 0.508)
			(layers "B.Cu" "B.Mask" "B.Paste")
			(net "P3V3_NODE1")
		)
		(pad "2" smd rect
			(at 0.40005 0 180)
			(size 0.4572 0.508)
			(layers "B.Cu" "B.Mask" "B.Paste")
			(net "GND")
		)
	)
	(footprint ""
		(layer "B.Cu")
		(at 154.06116 -174.537624)
		(property "Reference" "R747"
			(at -1.323086 12.476226 0)
			(unlocked yes)
			(layer "B.SilkS")
			(effects
				(font
					(size 0.7874 0.5842)
					(thickness 0.1524)
				)
				(justify left mirror)
			)
		)
		(property "Value" ""
			(at 0 0 0)
			(layer "B.Fab")
			(effects
				(font
					(size 1.27 1.27)
				)
				(justify mirror)
			)
		)
		(duplicate_pad_numbers_are_jumpers no)
		(fp_line
			(start -0.7874 -0.4064)
			(end -0.7874 0.4064)
			(stroke
				(width 0.1524)
				(type default)
			)
			(layer "B.SilkS")
		)
		(fp_line
			(start -0.7874 0.4064)
			(end 0.7874 0.4064)
			(stroke
				(width 0.1524)
				(type default)
			)
			(layer "B.SilkS")
		)
		(fp_line
			(start 0.7874 -0.4064)
			(end -0.7874 -0.4064)
			(stroke
				(width 0.1524)
				(type default)
			)
			(layer "B.SilkS")
		)
		(fp_line
			(start 0.7874 0.4064)
			(end 0.7874 -0.4064)
			(stroke
				(width 0.1524)
				(type default)
			)
			(layer "B.SilkS")
		)
		(fp_poly
			(pts
				(xy 0.508 0.2794) (xy 0.508 0.2286) (xy 0.635 0.2286) (xy 0.635 -0.254) (xy 0.5334 -0.254) (xy 0.5334 -0.2794)
				(xy -0.5334 -0.2794) (xy -0.5334 -0.254) (xy -0.635 -0.254) (xy -0.635 0.254) (xy -0.5334 0.254)
				(xy -0.5334 0.2794)
			)
			(stroke
				(width 0)
				(type default)
			)
			(fill no)
			(layer "B.CrtYd")
		)
		(pad "1" smd rect
			(at -0.40005 0 180)
			(size 0.4572 0.508)
			(layers "B.Cu" "B.Mask" "B.Paste")
			(net "T12_NODE2_EN")
		)
		(pad "2" smd rect
			(at 0.40005 0 180)
			(size 0.4572 0.508)
			(layers "B.Cu" "B.Mask" "B.Paste")
			(net "P5V_NODE1")
		)
	)
	(footprint ""
		(layer "B.Cu")
		(at 69.732652 -142.880842)
		(property "Reference" "TP8"
			(at -0.10287 -0.4826 270)
			(unlocked yes)
			(layer "B.SilkS")
			(effects
				(font
					(size 0.7874 0.5842)
					(thickness 0.1524)
				)
				(justify left mirror)
			)
		)
		(property "Value" ""
			(at 0 0 0)
			(layer "B.Fab")
			(effects
				(font
					(size 1.27 1.27)
				)
				(justify mirror)
			)
		)
		(duplicate_pad_numbers_are_jumpers no)
		(fp_poly
			(pts
				(arc
					(start 0 -0.381)
					(mid 0 0.381)
					(end 0 -0.381)
				)
			)
			(stroke
				(width 0)
				(type default)
			)
			(fill no)
			(layer "B.CrtYd")
		)
		(pad "1" smd circle
			(at 0 0 180)
			(size 0.762 0.762)
			(layers "B.Cu" "B.Mask" "B.Paste")
			(net "N3975090755")
		)
	)
	(footprint ""
		(layer "B.Cu")
		(at 65.194942 -28.091638)
		(property "Reference" "R204"
			(at -0.948182 -0.09271 0)
			(unlocked yes)
			(layer "B.SilkS")
			(effects
				(font
					(size 0.7874 0.5842)
					(thickness 0.1524)
				)
				(justify left mirror)
			)
		)
		(property "Value" ""
			(at 0 0 0)
			(layer "B.Fab")
			(effects
				(font
					(size 1.27 1.27)
				)
				(justify mirror)
			)
		)
		(duplicate_pad_numbers_are_jumpers no)
		(fp_line
			(start -0.7874 -0.4064)
			(end -0.7874 0.4064)
			(stroke
				(width 0.1524)
				(type default)
			)
			(layer "B.SilkS")
		)
		(fp_line
			(start -0.7874 0.4064)
			(end 0.7874 0.4064)
			(stroke
				(width 0.1524)
				(type default)
			)
			(layer "B.SilkS")
		)
		(fp_line
			(start 0.7874 -0.4064)
			(end -0.7874 -0.4064)
			(stroke
				(width 0.1524)
				(type default)
			)
			(layer "B.SilkS")
		)
		(fp_line
			(start 0.7874 0.4064)
			(end 0.7874 -0.4064)
			(stroke
				(width 0.1524)
				(type default)
			)
			(layer "B.SilkS")
		)
		(fp_poly
			(pts
				(xy 0.508 0.2794) (xy 0.508 0.2286) (xy 0.635 0.2286) (xy 0.635 -0.254) (xy 0.5334 -0.254) (xy 0.5334 -0.2794)
				(xy -0.5334 -0.2794) (xy -0.5334 -0.254) (xy -0.635 -0.254) (xy -0.635 0.254) (xy -0.5334 0.254)
				(xy -0.5334 0.2794)
			)
			(stroke
				(width 0)
				(type default)
			)
			(fill no)
			(layer "B.CrtYd")
		)
		(pad "1" smd rect
			(at -0.40005 0 180)
			(size 0.4572 0.508)
			(layers "B.Cu" "B.Mask" "B.Paste")
			(net "GND")
		)
		(pad "2" smd rect
			(at 0.40005 0 180)
			(size 0.4572 0.508)
			(layers "B.Cu" "B.Mask" "B.Paste")
			(net "PD_NODE1_DM8")
		)
	)
	(footprint ""
		(layer "B.Cu")
		(at 149.33676 -184.951624 90)
		(property "Reference" "R960"
			(at 4.357624 -3.09245 270)
			(unlocked yes)
			(layer "B.SilkS")
			(effects
				(font
					(size 0.7874 0.5842)
					(thickness 0.1524)
				)
				(justify left mirror)
			)
		)
		(property "Value" ""
			(at 0 0 90)
			(layer "B.Fab")
			(effects
				(font
					(size 1.27 1.27)
				)
				(justify mirror)
			)
		)
		(duplicate_pad_numbers_are_jumpers no)
		(fp_line
			(start 0.7874 -0.4064)
			(end -0.7874 -0.4064)
			(stroke
				(width 0.1524)
				(type default)
			)
			(layer "B.SilkS")
		)
		(fp_line
			(start -0.7874 -0.4064)
			(end -0.7874 0.4064)
			(stroke
				(width 0.1524)
				(type default)
			)
			(layer "B.SilkS")
		)
		(fp_line
			(start 0.7874 0.4064)
			(end 0.7874 -0.4064)
			(stroke
				(width 0.1524)
				(type default)
			)
			(layer "B.SilkS")
		)
		(fp_line
			(start -0.7874 0.4064)
			(end 0.7874 0.4064)
			(stroke
				(width 0.1524)
				(type default)
			)
			(layer "B.SilkS")
		)
		(fp_poly
			(pts
				(xy 0.508 0.2794) (xy 0.508 0.2286) (xy 0.635 0.2286) (xy 0.635 -0.254) (xy 0.5334 -0.254) (xy 0.5334 -0.2794)
				(xy -0.5334 -0.2794) (xy -0.5334 -0.254) (xy -0.635 -0.254) (xy -0.635 0.254) (xy -0.5334 0.254)
				(xy -0.5334 0.2794)
			)
			(stroke
				(width 0)
				(type default)
			)
			(fill no)
			(layer "B.CrtYd")
		)
		(pad "1" smd rect
			(at -0.40005 0 270)
			(size 0.4572 0.508)
			(layers "B.Cu" "B.Mask" "B.Paste")
			(net "UART_T11_NODE1_TXD")
		)
		(pad "2" smd rect
			(at 0.40005 0 270)
			(size 0.4572 0.508)
			(layers "B.Cu" "B.Mask" "B.Paste")
			(net "UART_T11_NODE1_TXD_R")
		)
	)
)
